G04 ================== begin FILE IDENTIFICATION RECORD ==================*
G04 Layout Name:  12433-1M.brd*
G04 Film Name:    BSILK*
G04 File Format:  Gerber RS274X*
G04 File Origin:  Cadence Allegro 16.2-S037*
G04 Origin Date:  Fri Dec 07 18:55:04 2012*
G04 *
G04 Layer:  VIA CLASS/FILMMASKBOTTOM*
G04 Layer:  REF DES/ASSEMBLY_BOTTOM*
G04 Layer:  PACKAGE GEOMETRY/SILKSCREEN_BOTTOM*
G04 Layer:  DRAWING FORMAT/LAYER_PCB_STORY*
G04 Layer:  DRAWING FORMAT/LAYER_SILK_B*
G04 Layer:  BOARD GEOMETRY/SILKSCREEN_BOTTOM*
G04 *
G04 Offset:    (0.00 0.00)*
G04 Mirror:    No*
G04 Mode:      Positive*
G04 Rotation:  0*
G04 FullContactRelief:  No*
G04 UndefLineWidth:     6.00*
G04 ================== end FILE IDENTIFICATION RECORD ====================*
%FSLAX35Y35*MOIN*%
%IR0*IPPOS*OFA0.00000B0.00000*MIA0B0*SFA1.00000B1.00000*%
%ADD10C,.032*%
%ADD11C,.02*%
%ADD12C,.012*%
%ADD13C,.006*%
G75*
%LPD*%
G75*
G54D10*
X72500Y1717000D03*
Y1699000D03*
X79000Y1766500D03*
X71500Y1760000D03*
X72500Y1733000D03*
X81000Y1802000D03*
X73000Y1813000D03*
X72000Y1798000D03*
X75500Y1838500D03*
X73000Y1847000D03*
X72500Y1830000D03*
X113024Y1452079D03*
X117122Y1448001D03*
X117195Y1456070D03*
X121338Y1452021D03*
X117024Y1452000D03*
X98500Y1717000D03*
Y1696500D03*
X99000Y1707000D03*
X109500Y1719500D03*
X110000Y1709500D03*
X109500Y1699000D03*
X119500Y1710110D03*
Y1696610D03*
X86500Y1713610D03*
Y1700110D03*
X119500Y1725110D03*
X111500Y1768500D03*
X108500Y1727000D03*
X117500Y1732000D03*
X119500Y1760000D03*
X97500Y1775500D03*
X86500Y1726000D03*
X87000Y1774110D03*
X119500Y1747110D03*
X110500Y1801000D03*
X88500Y1785000D03*
X97500Y1796000D03*
X98000Y1786000D03*
X86500Y1793110D03*
X108268Y1777300D03*
X107768Y1789110D03*
X120000Y1811500D03*
X119500Y1796500D03*
X114000Y1843500D03*
X97000Y1850500D03*
X120500Y1836500D03*
Y1850500D03*
X108500Y1851610D03*
X85100Y1844500D03*
X85700Y1852300D03*
X139000Y1696500D03*
Y1712500D03*
X181500Y1716500D03*
X158500D03*
X167500Y1716000D03*
X182000Y1704000D03*
X168500Y1705000D03*
X158500D03*
X163000Y1697000D03*
X174268Y1697110D03*
X152000D03*
Y1710610D03*
Y1725610D03*
X138500Y1727500D03*
X182000Y1726000D03*
X183600Y1765100D03*
X162500Y1773000D03*
X152500Y1771110D03*
X173268Y1776000D03*
X139000Y1800500D03*
X138000Y1824000D03*
X169000Y1781500D03*
X156500Y1782000D03*
X155500Y1798500D03*
X166500Y1798000D03*
X179000Y1798500D03*
X162000Y1790000D03*
X172768Y1790110D03*
X152000D03*
X139000Y1851000D03*
X138500Y1839500D03*
X161500Y1852500D03*
X183100Y1838300D03*
X173000Y1852610D03*
X151500Y1851110D03*
X184500Y1696500D03*
X185000Y1738500D03*
X185500Y1804500D03*
X186000Y1790000D03*
X185000Y1852500D03*
G54D11*
G01X-448201Y-82763D02*
Y-162763D01*
G01Y-118263D02*
X752899D01*
G01X-448201Y-162763D02*
X752899D01*
G01X-452201Y-66763D02*
G02I-12000J0D01*
G01X-457351D02*
G02I-6850J0D01*
G01X-464201Y-82763D02*
Y-50763D01*
G01X-448201Y-66763D02*
X-480201D01*
G01X-448201Y-82763D02*
X752899D01*
G01X-34601D02*
Y-162763D01*
G01X102899Y-82763D02*
Y-162763D01*
G01X217899Y-82763D02*
Y-162763D01*
G01X385399Y-82763D02*
Y-162763D01*
G01X555399Y-82763D02*
Y-162763D01*
G01X752899Y-82763D02*
Y-162763D01*
G01X780899Y-66763D02*
G02I-12000J0D01*
G01X775749D02*
G02I-6850J0D01*
G01X768899Y-82763D02*
Y-50763D01*
G01X784899Y-66763D02*
X752899D01*
G54D12*
G01X-206693Y39370D02*
X-175984D01*
G01X-214567Y200796D02*
Y170088D01*
G01Y467044D02*
Y436336D01*
G01Y734051D02*
Y703343D01*
G01Y1001310D02*
Y970602D01*
G01Y1265223D02*
Y1234515D01*
G01X-214568Y1532547D02*
Y1501839D01*
G01X-214567Y1798926D02*
Y1768218D01*
G01X-175984Y1929134D02*
X-206693D01*
G01X-76772Y7874D02*
Y31496D01*
G01X-76763Y1937008D02*
Y1960889D01*
G01X-7874Y11811D02*
Y42520D01*
G01X0Y11811D02*
Y42520D01*
G01X-7874Y278740D02*
Y309449D01*
G01X0Y278740D02*
Y309449D01*
G01X-7874Y545669D02*
Y576378D01*
G01X0Y545669D02*
Y576378D01*
G01Y862205D02*
Y831496D01*
G01X-7874Y862205D02*
Y831496D01*
G01Y1106299D02*
Y1137008D01*
G01X0Y1106299D02*
Y1137008D01*
G01Y1422835D02*
Y1392126D01*
G01X-7874Y1422835D02*
Y1392126D01*
G01X0Y1689764D02*
Y1659055D01*
G01X-7874Y1689764D02*
Y1659055D01*
G01Y1956693D02*
Y1925984D01*
G01X0Y1956693D02*
Y1925984D01*
G01X68889Y7615D02*
Y31496D01*
G01X116607Y1747835D02*
G03I-20150J0D01*
G01Y1823031D02*
G03I-20150J0D01*
G01X68898Y1960630D02*
Y1937008D01*
G01X168110Y39370D02*
X198819D01*
G01X178937Y1308590D02*
G03I0J20150D01*
G01X181567Y1747835D02*
G03I-20150J0D01*
G01Y1823031D02*
G03I-20150J0D01*
G01X198819Y1929134D02*
X168110D01*
G01X222441Y39370D02*
X253150D01*
G01X206693Y169291D02*
Y200000D01*
G01X214567Y169291D02*
Y200000D01*
G01X206693Y436220D02*
Y466929D01*
G01X214567Y436220D02*
Y466929D01*
G01X206693Y733858D02*
Y703149D01*
G01X214567Y733858D02*
Y703149D01*
G01X206693Y997637D02*
Y966928D01*
G01X214567Y997637D02*
Y966928D01*
G01Y1265355D02*
Y1234646D01*
G01X206693Y1265355D02*
Y1234646D01*
G01X214567Y1532284D02*
Y1501575D01*
G01X206693Y1532284D02*
Y1501575D01*
G01X214567Y1799213D02*
Y1768504D01*
G01X206693Y1799213D02*
Y1768504D01*
G01X253150Y1929134D02*
X222441D01*
G01X352362Y7874D02*
Y31496D01*
G01X352370Y1960889D02*
Y1937008D01*
G01X429134Y11811D02*
Y42520D01*
G01X421260Y11811D02*
Y42520D01*
G01X429134Y278740D02*
Y309449D01*
G01X421260Y278740D02*
Y309449D01*
G01X429134Y545669D02*
Y576378D01*
G01X421260Y545669D02*
Y576378D01*
G01X429134Y862205D02*
Y831496D01*
G01X421260Y862205D02*
Y831496D01*
G01X429134Y1106299D02*
Y1137008D01*
G01X421260Y1106299D02*
Y1137008D01*
G01X429134Y1422835D02*
Y1392126D01*
G01X421260Y1422835D02*
Y1392126D01*
G01X429134Y1689764D02*
Y1659055D01*
G01X421260Y1689764D02*
Y1659055D01*
G01X429134Y1956693D02*
Y1925984D01*
G01X421260Y1956693D02*
Y1925984D01*
G01X498023Y7615D02*
Y31496D01*
G01X498032Y1960630D02*
Y1937008D01*
G01X627953Y39370D02*
X597244D01*
G01X635684Y199210D02*
Y168502D01*
G01X635704Y466313D02*
Y435605D01*
G01X635795Y733708D02*
Y703000D01*
G01X635669Y999693D02*
Y968985D01*
G01X635696Y1264678D02*
Y1233970D01*
G01X635748Y1531930D02*
Y1501222D01*
G01X635827Y1799178D02*
Y1768470D01*
G01X627953Y1929134D02*
X597244D01*
G54D13*
G01X-430254Y-152763D02*
Y-135263D01*
G01X-421958D02*
X-430254Y-146055D01*
G01X-420648Y-152763D02*
X-426543Y-141097D01*
G01X-412973Y-152763D02*
Y-135263D01*
X-402929Y-152763D01*
Y-135263D01*
G01X-390451Y-152763D02*
X-392198Y-152471D01*
X-393726Y-151305D01*
X-395036Y-149555D01*
X-395910Y-147513D01*
X-396346Y-145180D01*
Y-142846D01*
X-395910Y-140513D01*
X-395036Y-138471D01*
X-393726Y-136722D01*
X-392198Y-135555D01*
X-390451Y-135263D01*
X-388705Y-135555D01*
X-387176Y-136722D01*
X-385866Y-138471D01*
X-384992Y-140513D01*
X-384556Y-142846D01*
Y-145180D01*
X-384992Y-147513D01*
X-385866Y-149555D01*
X-387176Y-151305D01*
X-388705Y-152471D01*
X-390451Y-152763D01*
G01X-377536D02*
X-368366Y-135263D01*
G01X-377536D02*
X-368366Y-152763D01*
G01X-362001Y-158596D02*
X-348901D01*
G01X-342099Y-152763D02*
Y-135263D01*
X-333803D01*
G01X-336859Y-143721D02*
X-342099D01*
G01X-325910Y-152763D02*
X-320451Y-135263D01*
X-314992Y-152763D01*
G01X-316958Y-146638D02*
X-323945D01*
G01X-307973Y-152763D02*
Y-135263D01*
X-297929Y-152763D01*
Y-135263D01*
G01X-263148Y-136722D02*
X-264458Y-135846D01*
X-265986Y-135263D01*
X-267733D01*
X-269698Y-136138D01*
X-271226Y-137596D01*
X-272318Y-139347D01*
X-273191Y-142263D01*
X-273410Y-144888D01*
X-272973Y-147513D01*
X-272318Y-149263D01*
X-271008Y-151013D01*
X-269479Y-152180D01*
X-267951Y-152763D01*
X-266423D01*
X-264894Y-152180D01*
X-263584Y-151305D01*
X-262492Y-150139D01*
G01X-250451Y-152763D02*
X-252198Y-152471D01*
X-253726Y-151305D01*
X-255036Y-149555D01*
X-255910Y-147513D01*
X-256346Y-145180D01*
Y-142846D01*
X-255910Y-140513D01*
X-255036Y-138471D01*
X-253726Y-136722D01*
X-252198Y-135555D01*
X-250451Y-135263D01*
X-248705Y-135555D01*
X-247176Y-136722D01*
X-245866Y-138471D01*
X-244992Y-140513D01*
X-244556Y-142846D01*
Y-145180D01*
X-244992Y-147513D01*
X-245866Y-149555D01*
X-247176Y-151305D01*
X-248705Y-152471D01*
X-250451Y-152763D01*
G01X-237973D02*
Y-135263D01*
X-227929Y-152763D01*
Y-135263D01*
G01X-215451D02*
Y-152763D01*
G01X-220473Y-135263D02*
X-210429D01*
G01X-202318Y-152763D02*
Y-135263D01*
X-196859D01*
X-195113Y-136138D01*
X-194021Y-137305D01*
X-193584Y-139638D01*
X-194021Y-141972D01*
X-195331Y-143430D01*
X-196859Y-144305D01*
X-202318D01*
G01X-196859D02*
X-193584Y-152763D01*
G01X-180451D02*
X-182198Y-152471D01*
X-183726Y-151305D01*
X-185036Y-149555D01*
X-185910Y-147513D01*
X-186346Y-145180D01*
Y-142846D01*
X-185910Y-140513D01*
X-185036Y-138471D01*
X-183726Y-136722D01*
X-182198Y-135555D01*
X-180451Y-135263D01*
X-178705Y-135555D01*
X-177176Y-136722D01*
X-175866Y-138471D01*
X-174992Y-140513D01*
X-174556Y-142846D01*
Y-145180D01*
X-174992Y-147513D01*
X-175866Y-149555D01*
X-177176Y-151305D01*
X-178705Y-152471D01*
X-180451Y-152763D01*
G01X-167318Y-135263D02*
Y-152763D01*
X-158584D01*
G01X-126205Y-143430D02*
X-125331Y-142555D01*
X-124676Y-141097D01*
X-124239Y-139054D01*
X-124676Y-137305D01*
X-125549Y-136138D01*
X-127078Y-135263D01*
X-132973D01*
Y-152763D01*
X-125768D01*
X-124239Y-151597D01*
X-123366Y-149846D01*
X-122929Y-147805D01*
X-123366Y-145763D01*
X-124676Y-144013D01*
X-126205Y-143430D01*
X-132973D01*
G01X-110451Y-152763D02*
X-112198Y-152471D01*
X-113726Y-151305D01*
X-115036Y-149555D01*
X-115910Y-147513D01*
X-116346Y-145180D01*
Y-142846D01*
X-115910Y-140513D01*
X-115036Y-138471D01*
X-113726Y-136722D01*
X-112198Y-135555D01*
X-110451Y-135263D01*
X-108705Y-135555D01*
X-107176Y-136722D01*
X-105866Y-138471D01*
X-104992Y-140513D01*
X-104556Y-142846D01*
Y-145180D01*
X-104992Y-147513D01*
X-105866Y-149555D01*
X-107176Y-151305D01*
X-108705Y-152471D01*
X-110451Y-152763D01*
G01X-98410D02*
X-92951Y-135263D01*
X-87492Y-152763D01*
G01X-89458Y-146638D02*
X-96445D01*
G01X-79818Y-152763D02*
Y-135263D01*
X-74359D01*
X-72613Y-136138D01*
X-71521Y-137305D01*
X-71084Y-139638D01*
X-71521Y-141972D01*
X-72831Y-143430D01*
X-74359Y-144305D01*
X-79818D01*
G01X-74359D02*
X-71084Y-152763D01*
G01X-62754D02*
Y-135263D01*
X-58388D01*
X-56641Y-136138D01*
X-55331Y-137305D01*
X-54239Y-139054D01*
X-53366Y-141097D01*
X-53148Y-144013D01*
X-53366Y-146930D01*
X-54239Y-148972D01*
X-55331Y-150722D01*
X-56641Y-151888D01*
X-58388Y-152763D01*
X-62754D01*
G01X-282378Y-107763D02*
Y-90263D01*
X-276701Y-104846D01*
X-271024Y-90263D01*
Y-107763D01*
G01X-259201D02*
X-260511Y-107471D01*
X-261821Y-106305D01*
X-262695Y-104263D01*
X-263131Y-101930D01*
X-262695Y-99596D01*
X-261821Y-97555D01*
X-260511Y-96388D01*
X-259201Y-96097D01*
X-257891Y-96388D01*
X-256581Y-97555D01*
X-255708Y-99596D01*
X-255489Y-101930D01*
X-255708Y-104263D01*
X-256581Y-106305D01*
X-257891Y-107471D01*
X-259201Y-107763D01*
G01X-237771Y-90263D02*
Y-107763D01*
G01Y-105139D02*
X-238644Y-106597D01*
X-239955Y-107471D01*
X-241483Y-107763D01*
X-243229Y-107180D01*
X-244539Y-105722D01*
X-245413Y-103972D01*
X-245631Y-101930D01*
X-245413Y-99888D01*
X-244539Y-98138D01*
X-243229Y-96680D01*
X-241483Y-96097D01*
X-239955Y-96388D01*
X-238863Y-96972D01*
X-237771Y-98138D01*
G01X-227476Y-99888D02*
X-220489D01*
X-221144Y-97846D01*
X-222236Y-96680D01*
X-223764Y-96097D01*
X-225293Y-96388D01*
X-226603Y-97263D01*
X-227476Y-99305D01*
X-227913Y-101055D01*
Y-102805D01*
X-227476Y-104555D01*
X-226384Y-106305D01*
X-225074Y-107471D01*
X-223546Y-107763D01*
X-222018Y-107180D01*
X-220489Y-105430D01*
G01X-206701Y-107763D02*
Y-90263D01*
G01X-901Y-152763D02*
Y-135263D01*
X-3521Y-138763D01*
G01Y-152763D02*
X1719D01*
G01X12451Y-138180D02*
X13761Y-136430D01*
X15289Y-135555D01*
X17036Y-135263D01*
X19219Y-135846D01*
X20747Y-137305D01*
X21184Y-139054D01*
X20966Y-140805D01*
X20092Y-142263D01*
X15726Y-145180D01*
X13761Y-147221D01*
X12451Y-150139D01*
X12014Y-152763D01*
X21184D01*
G01X36719D02*
Y-135263D01*
X28640Y-147805D01*
X39558D01*
G01X46796Y-149263D02*
X48105Y-151305D01*
X49852Y-152471D01*
X51817Y-152763D01*
X53564Y-152471D01*
X55311Y-151013D01*
X56402Y-149263D01*
X56621Y-147513D01*
X56184Y-145472D01*
X54656Y-144013D01*
X53127Y-143430D01*
X51162D01*
G01X53127D02*
X54437Y-142555D01*
X55529Y-141097D01*
X55966Y-139347D01*
X55529Y-137596D01*
X54437Y-136138D01*
X52472Y-135263D01*
X50507Y-135555D01*
X48542Y-136722D01*
G01X64296Y-149263D02*
X65605Y-151305D01*
X67352Y-152471D01*
X69317Y-152763D01*
X71064Y-152471D01*
X72811Y-151013D01*
X73902Y-149263D01*
X74121Y-147513D01*
X73684Y-145472D01*
X72156Y-144013D01*
X70627Y-143430D01*
X68662D01*
G01X70627D02*
X71937Y-142555D01*
X73029Y-141097D01*
X73466Y-139347D01*
X73029Y-137596D01*
X71937Y-136138D01*
X69972Y-135263D01*
X68007Y-135555D01*
X66042Y-136722D01*
G01X-14018Y-107763D02*
Y-90263D01*
X-8778D01*
X-7031Y-91138D01*
X-5721Y-93180D01*
X-5284Y-95513D01*
X-5721Y-97846D01*
X-6813Y-99596D01*
X-8778Y-100472D01*
X-14018D01*
G01X12652Y-91722D02*
X11342Y-90846D01*
X9814Y-90263D01*
X8067D01*
X6102Y-91138D01*
X4574Y-92596D01*
X3482Y-94347D01*
X2609Y-97263D01*
X2390Y-99888D01*
X2827Y-102513D01*
X3482Y-104263D01*
X4792Y-106013D01*
X6321Y-107180D01*
X7849Y-107763D01*
X9377D01*
X10906Y-107180D01*
X12216Y-106305D01*
X13308Y-105139D01*
G01X27095Y-98430D02*
X27969Y-97555D01*
X28624Y-96097D01*
X29061Y-94054D01*
X28624Y-92305D01*
X27751Y-91138D01*
X26222Y-90263D01*
X20327D01*
Y-107763D01*
X27532D01*
X29061Y-106597D01*
X29934Y-104846D01*
X30371Y-102805D01*
X29934Y-100763D01*
X28624Y-99013D01*
X27095Y-98430D01*
X20327D01*
G01X36299Y-113596D02*
X49399D01*
G01X55327Y-107763D02*
Y-90263D01*
X65371Y-107763D01*
Y-90263D01*
G01X77849Y-107763D02*
X76102Y-107471D01*
X74574Y-106305D01*
X73264Y-104555D01*
X72390Y-102513D01*
X71954Y-100180D01*
Y-97846D01*
X72390Y-95513D01*
X73264Y-93471D01*
X74574Y-91722D01*
X76102Y-90555D01*
X77849Y-90263D01*
X79595Y-90555D01*
X81124Y-91722D01*
X82434Y-93471D01*
X83308Y-95513D01*
X83744Y-97846D01*
Y-100180D01*
X83308Y-102513D01*
X82434Y-104555D01*
X81124Y-106305D01*
X79595Y-107471D01*
X77849Y-107763D01*
G01X128690Y-90263D02*
X134149Y-107763D01*
X139608Y-90263D01*
G01X156016Y-107763D02*
X147282D01*
Y-90263D01*
X156016D01*
G01X152522Y-98721D02*
X147282D01*
G01X164782Y-107763D02*
Y-90263D01*
X170241D01*
X171987Y-91138D01*
X173079Y-92305D01*
X173516Y-94638D01*
X173079Y-96972D01*
X171769Y-98430D01*
X170241Y-99305D01*
X164782D01*
G01X170241D02*
X173516Y-107763D01*
G01X186649Y-108346D02*
X186212Y-108055D01*
Y-107471D01*
X186649Y-107180D01*
X187086Y-107471D01*
Y-108055D01*
X186649Y-108346D01*
G01X151649Y-152763D02*
Y-135263D01*
X149029Y-138763D01*
G01Y-152763D02*
X154269D01*
G01X163472D02*
Y-135263D01*
X169149Y-149846D01*
X174826Y-135263D01*
Y-152763D01*
G01X334853Y-143430D02*
X333979Y-142555D01*
X333324Y-141097D01*
X332887Y-139054D01*
X333324Y-137305D01*
X334197Y-136138D01*
X335726Y-135263D01*
X341621D01*
Y-152763D01*
X334416D01*
X332887Y-151597D01*
X332014Y-149846D01*
X331577Y-147805D01*
X332014Y-145763D01*
X333324Y-144013D01*
X334853Y-143430D01*
X341621D01*
G01X323684Y-150430D02*
X321937Y-151888D01*
X319972Y-152763D01*
X318226D01*
X316479Y-151888D01*
X315169Y-150430D01*
X314514Y-148388D01*
X314951Y-146347D01*
X316042Y-144596D01*
X318007Y-143430D01*
X320627Y-142846D01*
X322156Y-141680D01*
X322811Y-139638D01*
X322374Y-137596D01*
X321282Y-136138D01*
X319754Y-135263D01*
X318226D01*
X316697Y-135846D01*
X315387Y-137305D01*
G01X304219Y-135263D02*
X298979D01*
G01X301599D02*
Y-152763D01*
G01X304219D02*
X298979D01*
G01X288466Y-135263D02*
Y-152763D01*
X279732D01*
G01X271402D02*
Y-135263D01*
G01X263106D02*
X271402Y-146055D01*
G01X261796Y-152763D02*
X267691Y-141097D01*
G01X253482Y-90263D02*
Y-107763D01*
X262216D01*
G01X279279D02*
Y-96097D01*
G01Y-98138D02*
X278406Y-96972D01*
X277095Y-96388D01*
X275567Y-96097D01*
X274039Y-96680D01*
X272729Y-97846D01*
X271855Y-99596D01*
X271419Y-101930D01*
X271855Y-104263D01*
X272729Y-106013D01*
X274039Y-107180D01*
X275567Y-107763D01*
X277095Y-107471D01*
X278406Y-106597D01*
X279279Y-105430D01*
G01X288264Y-113013D02*
X289574Y-113596D01*
X291321Y-113013D01*
X292412Y-111847D01*
X293286Y-110388D01*
X294595Y-105722D01*
X297434Y-96097D01*
G01X290447D02*
X294595Y-105722D01*
G01X307074Y-99888D02*
X314061D01*
X313406Y-97846D01*
X312314Y-96680D01*
X310786Y-96097D01*
X309257Y-96388D01*
X307947Y-97263D01*
X307074Y-99305D01*
X306637Y-101055D01*
Y-102805D01*
X307074Y-104555D01*
X308166Y-106305D01*
X309476Y-107471D01*
X311004Y-107763D01*
X312532Y-107180D01*
X314061Y-105430D01*
G01X324792Y-107763D02*
Y-96097D01*
G01Y-98430D02*
X325884Y-97263D01*
X326976Y-96388D01*
X328504Y-96097D01*
X329595Y-96388D01*
X330906Y-97263D01*
G01X342074Y-105722D02*
X343166Y-106888D01*
X344694Y-107763D01*
X346004D01*
X347314Y-107180D01*
X348187Y-106305D01*
X348624Y-105139D01*
X348406Y-103388D01*
X347532Y-102513D01*
X343602Y-100763D01*
X342729Y-98721D01*
X343166Y-97263D01*
X344039Y-96388D01*
X345349Y-96097D01*
X346659Y-96388D01*
X347969Y-97263D01*
G01X404346Y-107763D02*
Y-90263D01*
X408712D01*
X410459Y-91138D01*
X411769Y-92305D01*
X412861Y-94054D01*
X413734Y-96097D01*
X413952Y-99013D01*
X413734Y-101930D01*
X412861Y-103972D01*
X411769Y-105722D01*
X410459Y-106888D01*
X408712Y-107763D01*
X404346D01*
G01X423374Y-99888D02*
X430361D01*
X429706Y-97846D01*
X428614Y-96680D01*
X427086Y-96097D01*
X425557Y-96388D01*
X424247Y-97263D01*
X423374Y-99305D01*
X422937Y-101055D01*
Y-102805D01*
X423374Y-104555D01*
X424466Y-106305D01*
X425776Y-107471D01*
X427304Y-107763D01*
X428832Y-107180D01*
X430361Y-105430D01*
G01X440874Y-105722D02*
X441966Y-106888D01*
X443494Y-107763D01*
X444804D01*
X446114Y-107180D01*
X446987Y-106305D01*
X447424Y-105139D01*
X447206Y-103388D01*
X446332Y-102513D01*
X442402Y-100763D01*
X441529Y-98721D01*
X441966Y-97263D01*
X442839Y-96388D01*
X444149Y-96097D01*
X445459Y-96388D01*
X446769Y-97263D01*
G01X461649Y-96097D02*
Y-107763D01*
G01Y-91430D02*
X461212Y-91138D01*
Y-90555D01*
X461649Y-90263D01*
X462086Y-90555D01*
Y-91138D01*
X461649Y-91430D01*
G01X476092Y-112138D02*
X477621Y-113305D01*
X479367Y-113596D01*
X480895Y-113305D01*
X482206Y-111847D01*
X483079Y-109805D01*
Y-96097D01*
G01Y-98430D02*
X482206Y-97263D01*
X480895Y-96388D01*
X479367Y-96097D01*
X477621Y-96680D01*
X476529Y-97846D01*
X475655Y-99888D01*
X475219Y-101930D01*
X475437Y-103680D01*
X476311Y-105722D01*
X477621Y-107180D01*
X479367Y-107763D01*
X480677Y-107471D01*
X482206Y-106305D01*
X483079Y-105139D01*
G01X492937Y-107763D02*
Y-96097D01*
G01Y-99013D02*
X493811Y-97555D01*
X495121Y-96388D01*
X496867Y-96097D01*
X498395Y-96388D01*
X499706Y-97555D01*
X500361Y-99596D01*
Y-107763D01*
G01X510874Y-99888D02*
X517861D01*
X517206Y-97846D01*
X516114Y-96680D01*
X514586Y-96097D01*
X513057Y-96388D01*
X511747Y-97263D01*
X510874Y-99305D01*
X510437Y-101055D01*
Y-102805D01*
X510874Y-104555D01*
X511966Y-106305D01*
X513276Y-107471D01*
X514804Y-107763D01*
X516332Y-107180D01*
X517861Y-105430D01*
G01X528592Y-107763D02*
Y-96097D01*
G01Y-98430D02*
X529684Y-97263D01*
X530776Y-96388D01*
X532304Y-96097D01*
X533395Y-96388D01*
X534706Y-97263D01*
G01X448096Y-152763D02*
Y-135263D01*
X452462D01*
X454209Y-136138D01*
X455519Y-137305D01*
X456611Y-139054D01*
X457484Y-141097D01*
X457702Y-144013D01*
X457484Y-146930D01*
X456611Y-148972D01*
X455519Y-150722D01*
X454209Y-151888D01*
X452462Y-152763D01*
X448096D01*
G01X470399Y-141097D02*
Y-152763D01*
G01Y-136430D02*
X469962Y-136138D01*
Y-135555D01*
X470399Y-135263D01*
X470836Y-135555D01*
Y-136138D01*
X470399Y-136430D01*
G01X487899Y-152763D02*
X486589Y-152471D01*
X485279Y-151305D01*
X484405Y-149263D01*
X483969Y-146930D01*
X484405Y-144596D01*
X485279Y-142555D01*
X486589Y-141388D01*
X487899Y-141097D01*
X489209Y-141388D01*
X490519Y-142555D01*
X491392Y-144596D01*
X491611Y-146930D01*
X491392Y-149263D01*
X490519Y-151305D01*
X489209Y-152471D01*
X487899Y-152763D01*
G01X575349D02*
Y-135263D01*
X572729Y-138763D01*
G01Y-152763D02*
X577969D01*
G01X588701Y-138180D02*
X590011Y-136430D01*
X591539Y-135555D01*
X593286Y-135263D01*
X595469Y-135846D01*
X596997Y-137305D01*
X597434Y-139054D01*
X597216Y-140805D01*
X596342Y-142263D01*
X591976Y-145180D01*
X590011Y-147221D01*
X588701Y-150139D01*
X588264Y-152763D01*
X597434D01*
G01X606419Y-153346D02*
X614279Y-135263D01*
G01X627849D02*
X626102Y-135846D01*
X624792Y-137305D01*
X623919Y-139054D01*
X623264Y-141388D01*
X623046Y-144013D01*
X623264Y-146638D01*
X623919Y-148972D01*
X624792Y-150722D01*
X626102Y-152180D01*
X627849Y-152763D01*
X629595Y-152180D01*
X630906Y-150722D01*
X631779Y-148972D01*
X632434Y-146638D01*
X632652Y-144013D01*
X632434Y-141388D01*
X631779Y-139054D01*
X630906Y-137305D01*
X629595Y-135846D01*
X627849Y-135263D01*
G01X644912Y-152763D02*
X645349Y-148972D01*
X646004Y-145763D01*
X646877Y-142846D01*
X647969Y-139638D01*
X649716Y-135263D01*
X640982D01*
G01X658919Y-153346D02*
X666779Y-135263D01*
G01X676201Y-138180D02*
X677511Y-136430D01*
X679039Y-135555D01*
X680786Y-135263D01*
X682969Y-135846D01*
X684497Y-137305D01*
X684934Y-139054D01*
X684716Y-140805D01*
X683842Y-142263D01*
X679476Y-145180D01*
X677511Y-147221D01*
X676201Y-150139D01*
X675764Y-152763D01*
X684934D01*
G01X697849Y-135263D02*
X696102Y-135846D01*
X694792Y-137305D01*
X693919Y-139054D01*
X693264Y-141388D01*
X693046Y-144013D01*
X693264Y-146638D01*
X693919Y-148972D01*
X694792Y-150722D01*
X696102Y-152180D01*
X697849Y-152763D01*
X699595Y-152180D01*
X700906Y-150722D01*
X701779Y-148972D01*
X702434Y-146638D01*
X702652Y-144013D01*
X702434Y-141388D01*
X701779Y-139054D01*
X700906Y-137305D01*
X699595Y-135846D01*
X697849Y-135263D01*
G01X715349Y-152763D02*
Y-135263D01*
X712729Y-138763D01*
G01Y-152763D02*
X717969D01*
G01X728701Y-138180D02*
X730011Y-136430D01*
X731539Y-135555D01*
X733286Y-135263D01*
X735469Y-135846D01*
X736997Y-137305D01*
X737434Y-139054D01*
X737216Y-140805D01*
X736342Y-142263D01*
X731976Y-145180D01*
X730011Y-147221D01*
X728701Y-150139D01*
X728264Y-152763D01*
X737434D01*
G01X623046Y-107763D02*
Y-90263D01*
X627412D01*
X629159Y-91138D01*
X630469Y-92305D01*
X631561Y-94054D01*
X632434Y-96097D01*
X632652Y-99013D01*
X632434Y-101930D01*
X631561Y-103972D01*
X630469Y-105722D01*
X629159Y-106888D01*
X627412Y-107763D01*
X623046D01*
G01X649279D02*
Y-96097D01*
G01Y-98138D02*
X648406Y-96972D01*
X647095Y-96388D01*
X645567Y-96097D01*
X644039Y-96680D01*
X642729Y-97846D01*
X641855Y-99596D01*
X641419Y-101930D01*
X641855Y-104263D01*
X642729Y-106013D01*
X644039Y-107180D01*
X645567Y-107763D01*
X647095Y-107471D01*
X648406Y-106597D01*
X649279Y-105430D01*
G01X662849Y-90263D02*
Y-107763D01*
G01X659792Y-96097D02*
X665906D01*
G01X677074Y-99888D02*
X684061D01*
X683406Y-97846D01*
X682314Y-96680D01*
X680786Y-96097D01*
X679257Y-96388D01*
X677947Y-97263D01*
X677074Y-99305D01*
X676637Y-101055D01*
Y-102805D01*
X677074Y-104555D01*
X678166Y-106305D01*
X679476Y-107471D01*
X681004Y-107763D01*
X682532Y-107180D01*
X684061Y-105430D01*
G01X100975Y1779000D02*
Y1781500D01*
G01X99225D02*
Y1779000D01*
G01Y1780250D02*
X100975D01*
G01X97000Y1779000D02*
Y1781500D01*
X97500Y1781000D01*
G01Y1779000D02*
X96500D01*
G01X93900Y1781500D02*
X94233Y1781417D01*
X94483Y1781208D01*
X94650Y1780958D01*
X94775Y1780625D01*
X94817Y1780250D01*
X94775Y1779875D01*
X94650Y1779542D01*
X94483Y1779292D01*
X94233Y1779083D01*
X93900Y1779000D01*
X93567Y1779083D01*
X93317Y1779292D01*
X93150Y1779542D01*
X93025Y1779875D01*
X92983Y1780250D01*
X93025Y1780625D01*
X93150Y1780958D01*
X93317Y1781208D01*
X93567Y1781417D01*
X93900Y1781500D01*
G01X105425Y1846000D02*
Y1848500D01*
G01X103675D02*
Y1846000D01*
G01Y1847250D02*
X105425D01*
G01X102158Y1846292D02*
X101867Y1846083D01*
X101533Y1846000D01*
X101200Y1846083D01*
X100908Y1846333D01*
X100700Y1846708D01*
X100617Y1847083D01*
Y1847542D01*
X100700Y1847917D01*
X100908Y1848250D01*
X101158Y1848417D01*
X101450Y1848500D01*
X101783Y1848417D01*
X102033Y1848250D01*
X102200Y1848000D01*
X102283Y1847667D01*
X102200Y1847375D01*
X101992Y1847083D01*
X101742Y1846917D01*
X101450Y1846875D01*
X101117Y1846958D01*
X100867Y1847167D01*
X100617Y1847542D01*
G01X183475Y1352000D02*
Y1354500D01*
G01X181725D02*
Y1352000D01*
G01Y1353250D02*
X183475D01*
G01X179500Y1352000D02*
Y1354500D01*
X180000Y1354000D01*
G01Y1352000D02*
X179000D01*
G01X177317Y1352500D02*
X177067Y1352208D01*
X176733Y1352042D01*
X176358Y1352000D01*
X176025Y1352042D01*
X175692Y1352250D01*
X175483Y1352500D01*
X175442Y1352750D01*
X175525Y1353042D01*
X175817Y1353250D01*
X176108Y1353333D01*
X176483D01*
G01X176108D02*
X175858Y1353458D01*
X175650Y1353667D01*
X175567Y1353917D01*
X175650Y1354167D01*
X175858Y1354375D01*
X176233Y1354500D01*
X176608Y1354458D01*
X176983Y1354292D01*
G01X176876Y1770801D02*
Y1773301D01*
G01X175126D02*
Y1770801D01*
G01Y1772051D02*
X176876D01*
G01X172901Y1770801D02*
Y1773301D01*
X173401Y1772801D01*
G01Y1770801D02*
X172401D01*
G01X170593Y1772884D02*
X170343Y1773134D01*
X170051Y1773259D01*
X169718Y1773301D01*
X169301Y1773218D01*
X169009Y1773009D01*
X168926Y1772759D01*
X168968Y1772509D01*
X169134Y1772301D01*
X169968Y1771884D01*
X170343Y1771593D01*
X170593Y1771176D01*
X170676Y1770801D01*
X168926D01*
G01X166076Y1847700D02*
Y1850200D01*
G01X164326D02*
Y1847700D01*
G01Y1848950D02*
X166076D01*
G01X162101Y1847700D02*
Y1850200D01*
X162601Y1849700D01*
G01Y1847700D02*
X161601D01*
G01X159001D02*
Y1850200D01*
X159501Y1849700D01*
G01Y1847700D02*
X158501D01*
M02*
